#ISCELL
  mstr_symbols design_note *
  *
#ISCELL
  mstr_symbols intel_corp_bpage *
  *
#CELL
  mstr_discrete res *
  page178_i1
#ISCELL
  mstr_standard offpage *
  page178_i10
#CELL
  mstr_discrete res *
  page178_i11
#CELL
  mstr_discrete res *
  page178_i12
#CELL
  mstr_discrete res *
  page178_i13
#CELL
  mstr_discrete res *
  page178_i17
#CELL
  mstr_discrete res *
  page178_i18
#ISCELL
  mstr_symbols p3v3_stby *
  page178_i19
#CELL
  mstr_discrete res *
  page178_i2
#CELL
  mstr_discrete res *
  page178_i20
#CELL
  mstr_discrete res *
  page178_i21
#CELL
  mstr_discrete res *
  page178_i22
#CELL
  mstr_discrete res *
  page178_i23
#ISCELL
  mstr_standard offpage *
  page178_i24
#ISCELL
  mstr_standard offpage *
  page178_i25
#ISCELL
  mstr_standard offpage *
  page178_i26
#ISCELL
  mstr_standard offpage *
  page178_i3
#ISCELL
  mstr_standard offpage *
  page178_i4
#ISCELL
  mstr_symbols p3v3_stby *
  page178_i5
#ISCELL
  mstr_standard offpage *
  page178_i6
#ISCELL
  mstr_standard offpage *
  page178_i7
#CELL
  mstr_discrete res *
  page178_i8
#ISCELL
  mstr_standard offpage *
  page178_i9
